FILE_TYPE = MULTI_PHYS_TABLE;

PART 'SS15P3SM386A'

{========================================================================================}
:VALUE            | PART_TYPE | MATERIAL | PART_NUMBER    = STANDARD        | LIFECYCLE     | PART_NUMBER   | JEDEC_TYPE       | DESCRIPTION                         | MANUFTR | MANUF_PN         | RD_CMPLS_LVL | CMPLS_LVL | CLASS | DIP_SMD | FP_ECN              | FROM_PJ  | DATA                    | EE_CHECK_LIST | STATUS | PSL | PREFERENCE | CREATOR | CREATEDAY  | ESD_CDM | ESD_HBM | ESD_MM | MSD | PIN_LENGTH_LONG_PIN | PIN_LENGTH_SHORT_PIN ;
{========================================================================================}
 'SS15P3S-M3/86A' | 'SMLF'    | 'IC'     | 'BC015P3SZ00'(!) = ''               | ''               | 'BC015P3SZ00' |'TO277A_4-3X6-1'| 'DIODE SMD SS15P3S-M3/86A(30V,15A)' | 'SIL'   | 'SS15P3S-M3/86A' | 'EP(V1)'     | ''        | 'IC'  | ''      | 'SS15P3S-M386A.msg' | 'S9T-YC' | 'SIL_SS15P3S-M386A.pdf' | ''            | ''     | ''  | ''         | ''      | '20210421' | ''      | ''      | ''     | ''  | '0 MILS'            | '0 MILS'            
 'SS15P3S-M3/86A' | 'SMLF'    | 'EMPTY'  | 'BC015P3SZ00'(!) = ''               | ''               | 'BC015P3SZ00' |'TO277A_4-3X6-1'| 'DIODE SMD SS15P3S-M3/86A(30V,15A)' | 'SIL'   | 'SS15P3S-M3/86A' | 'EP(V1)'     | ''        | 'IC'  | ''      | 'SS15P3S-M386A.msg' | 'S9T-YC' | 'SIL_SS15P3S-M386A.pdf' | ''            | ''     | ''  | ''         | ''      | '20210421' | ''      | ''      | ''     | ''  | '0 MILS'            | '0 MILS'            

END_PART

END.

